# SCM (Grand Teton) — schematic netlist excerpt (pin names and nets, part order shuffled) for the footprints in the layout excerpt that follows; sources: Cadence DE-HDL packaged netlist, KiCad conversion of 12092022_DA0F0TMDCD0_F0T_Management_Board_D_brd_V3_OCP.brd

R157  Q_RES  33.2 1% CHIP  pkg 0402LF  page 13 : A = UART_BMC_1_TXD_R ; B = UART_BMC_1_TXD
C72  Q_CAP  0.1UF 25V 10% X7R  pkg 0402  page 16 : A = P1V2_AUX ; B = GND

(kicad_pcb
	(version 20260206)
	(generator "pcbnew")
	(generator_version "10.0")
	(general
		(thickness 1.6)
		(legacy_teardrops no)
	)
	(paper "A4")
	(title_block
		(title "12092022_DA0F0TMDCD0_F0T_Management_Board_D_brd_V3_OCP.brd")
		(comment 1 "Grand Teton / footprints 1175-1176 of 1440")
	)
	(layers
		(0 "F.Cu" signal "TOP")
		(4 "In1.Cu" signal "GND")
		(6 "In2.Cu" signal "IN1")
		(8 "In3.Cu" signal "GND1")
		(10 "In4.Cu" signal "IN2")
		(12 "In5.Cu" signal "VCC")
		(14 "In6.Cu" signal "VCC1")
		(16 "In7.Cu" signal "IN3")
		(18 "In8.Cu" signal "GND2")
		(20 "In9.Cu" signal "IN4")
		(22 "In10.Cu" signal "GND3")
		(2 "B.Cu" signal "BOTTOM")
		(9 "F.Adhes" user "F.Adhesive")
		(11 "B.Adhes" user "B.Adhesive")
		(13 "F.Paste" user "Package Geometry/Pastemask Top")
		(15 "B.Paste" user "Package Geometry/Pastemask Bottom")
		(5 "F.SilkS" user "Ref Des/Silkscreen Top")
		(7 "B.SilkS" user "Ref Des/Silkscreen Bottom")
		(1 "F.Mask" user "Board Geometry/Soldermask Top")
		(3 "B.Mask" user "Board Geometry/Soldermask Bottom")
		(17 "Dwgs.User" user "User.Drawings")
		(19 "Cmts.User" user "User.Comments")
		(21 "Eco1.User" user "User.Eco1")
		(23 "Eco2.User" user "User.Eco2")
		(25 "Edge.Cuts" user "Board Geometry/Outline")
		(27 "Margin" user)
		(31 "F.CrtYd" user "Package Geometry/Place Bound Top")
		(29 "B.CrtYd" user "Package Geometry/Place Bound Bottom")
		(35 "F.Fab" user "Ref Des/Assembly Top")
		(33 "B.Fab" user "Ref Des/Assembly Bottom")
	)
	(footprint ""
		(layer "B.Cu")
		(at 61.876686 -30.87751 -90)
		(property "Reference" "R157"
			(at 0 0 90)
			(layer "B.SilkS")
			(hide yes)
			(effects
				(font
					(size 1.27 1.27)
				)
				(justify mirror)
			)
		)
		(property "Value" ""
			(at 0 0 90)
			(layer "B.Fab")
			(effects
				(font
					(size 1.27 1.27)
				)
				(justify mirror)
			)
		)
		(duplicate_pad_numbers_are_jumpers no)
		(fp_line
			(start -0.7874 0.4064)
			(end 0.7874 0.4064)
			(stroke
				(width 0.1524)
				(type default)
			)
			(layer "B.SilkS")
		)
		(fp_line
			(start 0.7874 0.4064)
			(end 0.7874 -0.4064)
			(stroke
				(width 0.1524)
				(type default)
			)
			(layer "B.SilkS")
		)
		(fp_line
			(start -0.7874 -0.4064)
			(end -0.7874 0.4064)
			(stroke
				(width 0.1524)
				(type default)
			)
			(layer "B.SilkS")
		)
		(fp_line
			(start 0.7874 -0.4064)
			(end -0.7874 -0.4064)
			(stroke
				(width 0.1524)
				(type default)
			)
			(layer "B.SilkS")
		)
		(fp_line
			(start -0.67945 0.3048)
			(end -0.120396 0.3048)
			(stroke
				(width 0.1)
				(type default)
			)
			(layer "B.Fab")
		)
		(fp_line
			(start -0.120396 0.3048)
			(end -0.120396 0.2794)
			(stroke
				(width 0.1)
				(type default)
			)
			(layer "B.Fab")
		)
		(fp_line
			(start 0.12065 0.3048)
			(end 0.67945 0.3048)
			(stroke
				(width 0.1)
				(type default)
			)
			(layer "B.Fab")
		)
		(fp_line
			(start 0.67945 0.3048)
			(end 0.67945 -0.305054)
			(stroke
				(width 0.1)
				(type default)
			)
			(layer "B.Fab")
		)
		(fp_line
			(start -0.120396 0.2794)
			(end 0.12065 0.2794)
			(stroke
				(width 0.1)
				(type default)
			)
			(layer "B.Fab")
		)
		(fp_line
			(start 0.12065 0.2794)
			(end 0.12065 0.3048)
			(stroke
				(width 0.1)
				(type default)
			)
			(layer "B.Fab")
		)
		(fp_line
			(start -0.12065 -0.2794)
			(end -0.12065 -0.3048)
			(stroke
				(width 0.1)
				(type default)
			)
			(layer "B.Fab")
		)
		(fp_line
			(start 0.12065 -0.2794)
			(end -0.12065 -0.2794)
			(stroke
				(width 0.1)
				(type default)
			)
			(layer "B.Fab")
		)
		(fp_line
			(start -0.67945 -0.3048)
			(end -0.67945 0.3048)
			(stroke
				(width 0.1)
				(type default)
			)
			(layer "B.Fab")
		)
		(fp_line
			(start -0.12065 -0.3048)
			(end -0.67945 -0.3048)
			(stroke
				(width 0.1)
				(type default)
			)
			(layer "B.Fab")
		)
		(fp_line
			(start 0.12065 -0.305054)
			(end 0.12065 -0.2794)
			(stroke
				(width 0.1)
				(type default)
			)
			(layer "B.Fab")
		)
		(fp_line
			(start 0.67945 -0.305054)
			(end 0.12065 -0.305054)
			(stroke
				(width 0.1)
				(type default)
			)
			(layer "B.Fab")
		)
		(pad "1" smd circle
			(at 0.40005 0 90)
			(size 0 0)
			(layers "B.Cu" "B.Mask" "B.Paste")
			(net "UART_BMC_1_TXD_R")
		)
		(pad "2" smd circle
			(at -0.40005 0 90)
			(size 0 0)
			(layers "B.Cu" "B.Mask" "B.Paste")
			(net "UART_BMC_1_TXD")
		)
	)
	(footprint ""
		(layer "B.Cu")
		(at 49.205896 -47.67072 -90)
		(property "Reference" "C72"
			(at 0 0 90)
			(layer "B.SilkS")
			(hide yes)
			(effects
				(font
					(size 1.27 1.27)
				)
				(justify mirror)
			)
		)
		(property "Value" ""
			(at 0 0 90)
			(layer "B.Fab")
			(effects
				(font
					(size 1.27 1.27)
				)
				(justify mirror)
			)
		)
		(duplicate_pad_numbers_are_jumpers no)
		(fp_line
			(start -0.7874 0.4064)
			(end 0.7874 0.4064)
			(stroke
				(width 0.1524)
				(type default)
			)
			(layer "B.SilkS")
		)
		(fp_line
			(start 0.7874 0.4064)
			(end 0.7874 -0.4064)
			(stroke
				(width 0.1524)
				(type default)
			)
			(layer "B.SilkS")
		)
		(fp_line
			(start -0.7874 -0.4064)
			(end -0.7874 0.4064)
			(stroke
				(width 0.1524)
				(type default)
			)
			(layer "B.SilkS")
		)
		(fp_line
			(start 0.7874 -0.4064)
			(end -0.7874 -0.4064)
			(stroke
				(width 0.1524)
				(type default)
			)
			(layer "B.SilkS")
		)
		(fp_line
			(start -0.67945 0.3048)
			(end -0.120396 0.3048)
			(stroke
				(width 0.1)
				(type default)
			)
			(layer "B.Fab")
		)
		(fp_line
			(start -0.120396 0.3048)
			(end -0.120396 0.2794)
			(stroke
				(width 0.1)
				(type default)
			)
			(layer "B.Fab")
		)
		(fp_line
			(start 0.12065 0.3048)
			(end 0.67945 0.3048)
			(stroke
				(width 0.1)
				(type default)
			)
			(layer "B.Fab")
		)
		(fp_line
			(start 0.67945 0.3048)
			(end 0.67945 -0.305054)
			(stroke
				(width 0.1)
				(type default)
			)
			(layer "B.Fab")
		)
		(fp_line
			(start -0.120396 0.2794)
			(end 0.12065 0.2794)
			(stroke
				(width 0.1)
				(type default)
			)
			(layer "B.Fab")
		)
		(fp_line
			(start 0.12065 0.2794)
			(end 0.12065 0.3048)
			(stroke
				(width 0.1)
				(type default)
			)
			(layer "B.Fab")
		)
		(fp_line
			(start -0.12065 -0.2794)
			(end -0.12065 -0.3048)
			(stroke
				(width 0.1)
				(type default)
			)
			(layer "B.Fab")
		)
		(fp_line
			(start 0.12065 -0.2794)
			(end -0.12065 -0.2794)
			(stroke
				(width 0.1)
				(type default)
			)
			(layer "B.Fab")
		)
		(fp_line
			(start -0.67945 -0.3048)
			(end -0.67945 0.3048)
			(stroke
				(width 0.1)
				(type default)
			)
			(layer "B.Fab")
		)
		(fp_line
			(start -0.12065 -0.3048)
			(end -0.67945 -0.3048)
			(stroke
				(width 0.1)
				(type default)
			)
			(layer "B.Fab")
		)
		(fp_line
			(start 0.12065 -0.305054)
			(end 0.12065 -0.2794)
			(stroke
				(width 0.1)
				(type default)
			)
			(layer "B.Fab")
		)
		(fp_line
			(start 0.67945 -0.305054)
			(end 0.12065 -0.305054)
			(stroke
				(width 0.1)
				(type default)
			)
			(layer "B.Fab")
		)
		(pad "1" smd circle
			(at 0.40005 0 90)
			(size 0 0)
			(layers "B.Cu" "B.Mask" "B.Paste")
			(net "P1V2_AUX")
		)
		(pad "2" smd circle
			(at -0.40005 0 90)
			(size 0 0)
			(layers "B.Cu" "B.Mask" "B.Paste")
			(net "GND")
		)
	)
)
